# T6G (Grand Teton) — schematic netlist excerpt (pin names and nets, part order shuffled) for the footprints in the layout excerpt that follows; sources: Cadence DE-HDL packaged netlist, KiCad conversion of 04192023_DAF0TMB3IC0_F0TG_MB_C_brd_V02_OCP.brd

C1572  Q_CAP_DIFFBUS  DIFF BUS_0.22UF 6.3V 20% X6S  pkg C0201  page 65 : \1\ = P5E_CPU0_G3_TX_C_DN<3> ; \2\ = P5E_CPU0_G3_TX_DN<3>
C9007  Q_CAP  0.1UF 25V 10% X7R  pkg 0402  page 136 : A = P3V3_AUX ; B = GND

(kicad_pcb
	(version 20260206)
	(generator "pcbnew")
	(generator_version "10.0")
	(general
		(thickness 1.6)
		(legacy_teardrops no)
	)
	(paper "A4")
	(title_block
		(title "04192023_DAF0TMB3IC0_F0TG_MB_C_brd_V02_OCP.brd")
		(comment 1 "Grand Teton / footprints 3707-3708 of 8354")
	)
	(layers
		(0 "F.Cu" signal "TOP")
		(4 "In1.Cu" signal "GND")
		(6 "In2.Cu" signal "IN1")
		(8 "In3.Cu" signal "GND1")
		(10 "In4.Cu" signal "IN2")
		(12 "In5.Cu" signal "GND2")
		(14 "In6.Cu" signal "IN3")
		(16 "In7.Cu" signal "GND3")
		(18 "In8.Cu" signal "VCC")
		(20 "In9.Cu" signal "VCC1")
		(22 "In10.Cu" signal "GND4")
		(24 "In11.Cu" signal "IN4")
		(26 "In12.Cu" signal "GND5")
		(28 "In13.Cu" signal "IN5")
		(30 "In14.Cu" signal "GND6")
		(32 "In15.Cu" signal "IN6")
		(34 "In16.Cu" signal "GND7")
		(2 "B.Cu" signal "BOTTOM")
		(9 "F.Adhes" user "F.Adhesive")
		(11 "B.Adhes" user "B.Adhesive")
		(13 "F.Paste" user "Package Geometry/Pastemask Top")
		(15 "B.Paste" user "Package Geometry/Pastemask Bottom")
		(5 "F.SilkS" user "Ref Des/Silkscreen Top")
		(7 "B.SilkS" user "Ref Des/Silkscreen Bottom")
		(1 "F.Mask" user "Board Geometry/Soldermask Top")
		(3 "B.Mask" user "Board Geometry/Soldermask Bottom")
		(17 "Dwgs.User" user "User.Drawings")
		(19 "Cmts.User" user "User.Comments")
		(21 "Eco1.User" user "User.Eco1")
		(23 "Eco2.User" user "User.Eco2")
		(25 "Edge.Cuts" user "Board Geometry/Outline")
		(27 "Margin" user)
		(31 "F.CrtYd" user "Package Geometry/Place Bound Top")
		(29 "B.CrtYd" user "Package Geometry/Place Bound Bottom")
		(35 "F.Fab" user "Ref Des/Assembly Top")
		(33 "B.Fab" user "Ref Des/Assembly Bottom")
	)
	(footprint ""
		(layer "F.Cu")
		(at 153.543 -104.648)
		(property "Reference" "C9007"
			(at 0 0 0)
			(layer "F.SilkS")
			(hide yes)
			(effects
				(font
					(size 1.27 1.27)
				)
			)
		)
		(property "Value" ""
			(at 0 0 0)
			(layer "F.Fab")
			(effects
				(font
					(size 1.27 1.27)
				)
			)
		)
		(duplicate_pad_numbers_are_jumpers no)
		(fp_line
			(start -0.7874 -0.4064)
			(end 0.7874 -0.4064)
			(stroke
				(width 0.1524)
				(type default)
			)
			(layer "F.SilkS")
		)
		(fp_line
			(start -0.7874 0.4064)
			(end -0.7874 -0.4064)
			(stroke
				(width 0.1524)
				(type default)
			)
			(layer "F.SilkS")
		)
		(fp_line
			(start 0.7874 -0.4064)
			(end 0.7874 0.4064)
			(stroke
				(width 0.1524)
				(type default)
			)
			(layer "F.SilkS")
		)
		(fp_line
			(start 0.7874 0.4064)
			(end -0.7874 0.4064)
			(stroke
				(width 0.1524)
				(type default)
			)
			(layer "F.SilkS")
		)
		(fp_line
			(start -0.67945 -0.305054)
			(end -0.12065 -0.305054)
			(stroke
				(width 0.1)
				(type default)
			)
			(layer "F.Fab")
		)
		(fp_line
			(start -0.67945 0.3048)
			(end -0.67945 -0.305054)
			(stroke
				(width 0.1)
				(type default)
			)
			(layer "F.Fab")
		)
		(fp_line
			(start -0.12065 -0.305054)
			(end -0.12065 -0.2794)
			(stroke
				(width 0.1)
				(type default)
			)
			(layer "F.Fab")
		)
		(fp_line
			(start -0.12065 -0.2794)
			(end 0.12065 -0.2794)
			(stroke
				(width 0.1)
				(type default)
			)
			(layer "F.Fab")
		)
		(fp_line
			(start -0.12065 0.2794)
			(end -0.12065 0.3048)
			(stroke
				(width 0.1)
				(type default)
			)
			(layer "F.Fab")
		)
		(fp_line
			(start -0.12065 0.3048)
			(end -0.67945 0.3048)
			(stroke
				(width 0.1)
				(type default)
			)
			(layer "F.Fab")
		)
		(fp_line
			(start 0.120396 0.2794)
			(end -0.12065 0.2794)
			(stroke
				(width 0.1)
				(type default)
			)
			(layer "F.Fab")
		)
		(fp_line
			(start 0.120396 0.3048)
			(end 0.120396 0.2794)
			(stroke
				(width 0.1)
				(type default)
			)
			(layer "F.Fab")
		)
		(fp_line
			(start 0.12065 -0.3048)
			(end 0.67945 -0.3048)
			(stroke
				(width 0.1)
				(type default)
			)
			(layer "F.Fab")
		)
		(fp_line
			(start 0.12065 -0.2794)
			(end 0.12065 -0.3048)
			(stroke
				(width 0.1)
				(type default)
			)
			(layer "F.Fab")
		)
		(fp_line
			(start 0.67945 -0.3048)
			(end 0.67945 0.3048)
			(stroke
				(width 0.1)
				(type default)
			)
			(layer "F.Fab")
		)
		(fp_line
			(start 0.67945 0.3048)
			(end 0.120396 0.3048)
			(stroke
				(width 0.1)
				(type default)
			)
			(layer "F.Fab")
		)
		(pad "1" smd circle
			(at -0.40005 0)
			(size 0 0)
			(layers "F.Cu" "F.Mask" "F.Paste")
			(net "P3V3_AUX")
		)
		(pad "2" smd circle
			(at 0.40005 0)
			(size 0 0)
			(layers "F.Cu" "F.Mask" "F.Paste")
			(net "GND")
		)
	)
	(footprint ""
		(layer "F.Cu")
		(at 423.841164 -16.100298 90)
		(property "Reference" "C1572"
			(at 0 0 90)
			(layer "F.SilkS")
			(hide yes)
			(effects
				(font
					(size 1.27 1.27)
				)
			)
		)
		(property "Value" ""
			(at 0 0 90)
			(layer "F.Fab")
			(effects
				(font
					(size 1.27 1.27)
				)
			)
		)
		(duplicate_pad_numbers_are_jumpers no)
		(fp_line
			(start 0.299974 -0.150114)
			(end 0.299974 0.150114)
			(stroke
				(width 0.1)
				(type default)
			)
			(layer "F.Fab")
		)
		(fp_line
			(start -0.299974 -0.150114)
			(end 0.299974 -0.150114)
			(stroke
				(width 0.1)
				(type default)
			)
			(layer "F.Fab")
		)
		(fp_line
			(start 0.299974 0.150114)
			(end -0.299974 0.150114)
			(stroke
				(width 0.1)
				(type default)
			)
			(layer "F.Fab")
		)
		(fp_line
			(start -0.299974 0.150114)
			(end -0.299974 -0.150114)
			(stroke
				(width 0.1)
				(type default)
			)
			(layer "F.Fab")
		)
		(pad "1" smd rect
			(at -0.2667 0 90)
			(size 0.3048 0.381)
			(layers "F.Cu" "F.Mask" "F.Paste")
			(net "P5E_CPU0_G3_TX_C_DN<3>")
		)
		(pad "2" smd rect
			(at 0.2667 0 90)
			(size 0.3048 0.381)
			(layers "F.Cu" "F.Mask" "F.Paste")
			(net "P5E_CPU0_G3_TX_DN<3>")
		)
	)
)
